(kicad_pcb
	(version 20241229)
	(generator "pcbnew")
	(generator_version "9.0")
	(general
		(thickness 1.294)
		(legacy_teardrops no)
	)
	(paper "A3")
	(title_block
		(title "Kintex 410T devboard")
		(date "2024-04-03")
		(rev "1.1.2")
		(comment 9 "footprints 192-196 of 975")
	)
	(layers
		(0 "F.Cu" mixed)
		(4 "In1.Cu" power)
		(6 "In2.Cu" power)
		(8 "In3.Cu" mixed)
		(10 "In4.Cu" power)
		(12 "In5.Cu" mixed)
		(14 "In6.Cu" power)
		(16 "In7.Cu" mixed)
		(18 "In8.Cu" power)
		(2 "B.Cu" mixed)
		(9 "F.Adhes" user "F.Adhesive")
		(11 "B.Adhes" user "B.Adhesive")
		(13 "F.Paste" user)
		(15 "B.Paste" user)
		(5 "F.SilkS" user "F.Silkscreen")
		(7 "B.SilkS" user "B.Silkscreen")
		(1 "F.Mask" user)
		(3 "B.Mask" user)
		(17 "Dwgs.User" user "User.Drawings")
		(19 "Cmts.User" user "User.Comments")
		(21 "Eco1.User" user "User.Eco1")
		(23 "Eco2.User" user "User.Eco2")
		(25 "Edge.Cuts" user)
		(27 "Margin" user)
		(31 "F.CrtYd" user "F.Courtyard")
		(29 "B.CrtYd" user "B.Courtyard")
		(35 "F.Fab" user)
		(33 "B.Fab" user)
	)
	(footprint "antmicro-footprints:SC70-3"
		(layer "F.Cu")
		(at 210.1 78.78 90)
		(property "Reference" "Q2"
			(at -2.32 0.2 180)
			(layer "F.SilkS")
			(effects
				(font
					(size 0.7 0.7)
					(thickness 0.15)
				)
				(justify left bottom)
			)
		)
		(property "Value" "BSS138PW"
			(at 0 2.3 90)
			(layer "F.Fab")
			(effects
				(font
					(size 0.7 0.7)
					(thickness 0.15)
				)
				(justify left bottom)
			)
		)
		(property "Description" "Power MOSFET, N Channel, 60 V, 320 mA, 0.9 ohm, SOT-323, Surface Mount"
			(at 0 0 90)
			(layer "F.Fab")
			(hide yes)
			(effects
				(font
					(size 1.27 1.27)
					(thickness 0.15)
				)
			)
		)
		(property "Author" "Antmicro"
			(at 288.88 -131.32 0)
			(layer "F.Fab")
			(hide yes)
			(effects
				(font
					(size 1 1)
					(thickness 0.15)
				)
			)
		)
		(property "License" "Apache-2.0"
			(at 288.88 -131.32 0)
			(layer "F.Fab")
			(hide yes)
			(effects
				(font
					(size 1 1)
					(thickness 0.15)
				)
			)
		)
		(property "MPN" "BSS138PW"
			(at 288.88 -131.32 0)
			(layer "F.Fab")
			(hide yes)
			(effects
				(font
					(size 1 1)
					(thickness 0.15)
				)
			)
		)
		(property "Manufacturer" "Nexperia"
			(at 288.88 -131.32 0)
			(layer "F.Fab")
			(hide yes)
			(effects
				(font
					(size 1 1)
					(thickness 0.15)
				)
			)
		)
		(sheetname "FPGA Config")
		(sheetfile "fpga-config.kicad_sch")
		(attr smd)
		(fp_line
			(start -0.3 -1)
			(end 0.627 -0.999)
			(stroke
				(width 0.15)
				(type solid)
			)
			(layer "F.SilkS")
		)
		(fp_line
			(start 0.627 -0.6)
			(end 0.627 -0.999)
			(stroke
				(width 0.15)
				(type solid)
			)
			(layer "F.SilkS")
		)
		(fp_line
			(start 0.627 0.6)
			(end 0.627 1.001)
			(stroke
				(width 0.15)
				(type solid)
			)
			(layer "F.SilkS")
		)
		(fp_line
			(start -0.3 1)
			(end 0.627 1.001)
			(stroke
				(width 0.15)
				(type solid)
			)
			(layer "F.SilkS")
		)
		(fp_line
			(start 0.9 -1.3)
			(end 0.9 -0.4)
			(stroke
				(width 0.05)
				(type solid)
			)
			(layer "F.CrtYd")
		)
		(fp_line
			(start -0.9 -1.3)
			(end 0.9 -1.3)
			(stroke
				(width 0.05)
				(type solid)
			)
			(layer "F.CrtYd")
		)
		(fp_line
			(start -0.9 -1.3)
			(end -0.9 -1)
			(stroke
				(width 0.05)
				(type solid)
			)
			(layer "F.CrtYd")
		)
		(fp_line
			(start -0.9 -1)
			(end -1.4 -1)
			(stroke
				(width 0.05)
				(type solid)
			)
			(layer "F.CrtYd")
		)
		(fp_line
			(start 1.4 -0.4)
			(end 1.4 0.4)
			(stroke
				(width 0.05)
				(type solid)
			)
			(layer "F.CrtYd")
		)
		(fp_line
			(start 0.9 -0.4)
			(end 1.4 -0.4)
			(stroke
				(width 0.05)
				(type solid)
			)
			(layer "F.CrtYd")
		)
		(fp_line
			(start 1.4 0.4)
			(end 0.9 0.4)
			(stroke
				(width 0.05)
				(type solid)
			)
			(layer "F.CrtYd")
		)
		(fp_line
			(start 0.9 0.4)
			(end 0.9 1.3)
			(stroke
				(width 0.05)
				(type solid)
			)
			(layer "F.CrtYd")
		)
		(fp_line
			(start -0.9 1)
			(end -1.4 1)
			(stroke
				(width 0.05)
				(type solid)
			)
			(layer "F.CrtYd")
		)
		(fp_line
			(start -1.4 1)
			(end -1.4 -1)
			(stroke
				(width 0.05)
				(type solid)
			)
			(layer "F.CrtYd")
		)
		(fp_line
			(start 0.9 1.3)
			(end -0.9 1.3)
			(stroke
				(width 0.05)
				(type solid)
			)
			(layer "F.CrtYd")
		)
		(fp_line
			(start -0.9 1.3)
			(end -0.9 1)
			(stroke
				(width 0.05)
				(type solid)
			)
			(layer "F.CrtYd")
		)
		(fp_rect
			(start -0.623 -0.999)
			(end 0.627 1.001)
			(stroke
				(width 0.15)
				(type solid)
			)
			(fill no)
			(layer "F.Fab")
		)
		(pad "1" smd rect
			(at -1.051 -0.65 180)
			(size 0.6 0.6)
			(layers "F.Cu" "F.Mask" "F.Paste")
			(net 257 "/FPGA Config/INIT_B")
			(pinfunction "G")
			(pintype "bidirectional")
		)
		(pad "2" smd rect
			(at -1.051 0.65 180)
			(size 0.6 0.6)
			(layers "F.Cu" "F.Mask" "F.Paste")
			(net 1 "GND")
			(pinfunction "S")
			(pintype "bidirectional")
		)
		(pad "3" smd rect
			(at 1.05 0 180)
			(size 0.6 0.6)
			(layers "F.Cu" "F.Mask" "F.Paste")
			(net 336 "Net-(Q2-D)")
			(pinfunction "D")
			(pintype "bidirectional")
		)
	)
	(footprint "antmicro-footprints:R_0402_1005Metric"
		(layer "F.Cu")
		(at 260.3 133.7 -90)
		(descr "Resistor SMD 0402")
		(tags "resistor SMD 0402")
		(property "Reference" "R158"
			(at 0.9 0.5 270)
			(layer "F.SilkS")
			(effects
				(font
					(size 0.7 0.7)
					(thickness 0.15)
				)
				(justify left bottom)
			)
		)
		(property "Value" "R_10k_0402"
			(at 0 1.4 270)
			(layer "F.Fab")
			(effects
				(font
					(size 0.7 0.7)
					(thickness 0.15)
				)
				(justify left bottom)
			)
		)
		(property "Description" "SMD Chip Resistor, 10 kohm, ± 1%, 62.5 mW, 0402 [1005 Metric], Thick Film, General Purpose"
			(at 0 0 270)
			(layer "F.Fab")
			(hide yes)
			(effects
				(font
					(size 1.27 1.27)
					(thickness 0.15)
				)
			)
		)
		(property "Author" "Antmicro"
			(at 126.6 394 0)
			(layer "F.Fab")
			(hide yes)
			(effects
				(font
					(size 1 1)
					(thickness 0.15)
				)
			)
		)
		(property "License" "Apache-2.0"
			(at 126.6 394 0)
			(layer "F.Fab")
			(hide yes)
			(effects
				(font
					(size 1 1)
					(thickness 0.15)
				)
			)
		)
		(property "MPN" "CR0402-FX-1002GLF"
			(at 126.6 394 0)
			(layer "F.Fab")
			(hide yes)
			(effects
				(font
					(size 1 1)
					(thickness 0.15)
				)
			)
		)
		(property "Manufacturer" "Bourns"
			(at 126.6 394 0)
			(layer "F.Fab")
			(hide yes)
			(effects
				(font
					(size 1 1)
					(thickness 0.15)
				)
			)
		)
		(property "Tolerance" "1%"
			(at 126.6 394 0)
			(layer "F.Fab")
			(hide yes)
			(effects
				(font
					(size 1 1)
					(thickness 0.15)
				)
			)
		)
		(property "Val" "10k"
			(at 126.6 394 0)
			(layer "F.Fab")
			(hide yes)
			(effects
				(font
					(size 1 1)
					(thickness 0.15)
				)
			)
		)
		(sheetname "USB PHY")
		(sheetfile "usb-phy.kicad_sch")
		(attr smd)
		(fp_rect
			(start -0.925 -0.47)
			(end 0.925 0.47)
			(stroke
				(width 0.05)
				(type default)
			)
			(fill no)
			(layer "F.CrtYd")
		)
		(fp_rect
			(start -0.5 -0.25)
			(end 0.5 0.25)
			(stroke
				(width 0.15)
				(type solid)
			)
			(fill no)
			(layer "F.Fab")
		)
		(pad "1" smd roundrect
			(at -0.48 0 270)
			(size 0.59 0.64)
			(layers "F.Cu" "F.Mask" "F.Paste")
			(roundrect_rratio 0.25)
			(net 707 "/USB PHY/FTDI_3V3")
			(pintype "passive")
		)
		(pad "2" smd roundrect
			(at 0.48 0 270)
			(size 0.59 0.64)
			(layers "F.Cu" "F.Mask" "F.Paste")
			(roundrect_rratio 0.25)
			(net 918 "/USB PHY/FTDI_PWREN")
			(pintype "passive")
		)
	)
	(footprint "antmicro-footprints:SC70-3"
		(layer "F.Cu")
		(at 258.4 81.4)
		(property "Reference" "Q16"
			(at -1.6 1.1 90)
			(layer "F.SilkS")
			(effects
				(font
					(size 0.7 0.7)
					(thickness 0.15)
				)
				(justify left bottom)
			)
		)
		(property "Value" "BSS138PW"
			(at 0 2.3 0)
			(layer "F.Fab")
			(effects
				(font
					(size 0.7 0.7)
					(thickness 0.15)
				)
				(justify left bottom)
			)
		)
		(property "Description" "Power MOSFET, N Channel, 60 V, 320 mA, 0.9 ohm, SOT-323, Surface Mount"
			(at 0 0 0)
			(layer "F.Fab")
			(hide yes)
			(effects
				(font
					(size 1.27 1.27)
					(thickness 0.15)
				)
			)
		)
		(property "Author" "Antmicro"
			(at 0 0 0)
			(layer "F.Fab")
			(hide yes)
			(effects
				(font
					(size 1 1)
					(thickness 0.15)
				)
			)
		)
		(property "License" "Apache-2.0"
			(at 0 0 0)
			(layer "F.Fab")
			(hide yes)
			(effects
				(font
					(size 1 1)
					(thickness 0.15)
				)
			)
		)
		(property "MPN" "BSS138PW"
			(at 0 0 0)
			(layer "F.Fab")
			(hide yes)
			(effects
				(font
					(size 1 1)
					(thickness 0.15)
				)
			)
		)
		(property "Manufacturer" "Nexperia"
			(at 0 0 0)
			(layer "F.Fab")
			(hide yes)
			(effects
				(font
					(size 1 1)
					(thickness 0.15)
				)
			)
		)
		(sheetname "User GPIO + LED + button + DIP switch")
		(sheetfile "user-gpio.kicad_sch")
		(attr smd)
		(fp_line
			(start -0.3 -1)
			(end 0.627 -0.999)
			(stroke
				(width 0.15)
				(type solid)
			)
			(layer "F.SilkS")
		)
		(fp_line
			(start -0.3 1)
			(end 0.627 1.001)
			(stroke
				(width 0.15)
				(type solid)
			)
			(layer "F.SilkS")
		)
		(fp_line
			(start 0.627 -0.6)
			(end 0.627 -0.999)
			(stroke
				(width 0.15)
				(type solid)
			)
			(layer "F.SilkS")
		)
		(fp_line
			(start 0.627 0.6)
			(end 0.627 1.001)
			(stroke
				(width 0.15)
				(type solid)
			)
			(layer "F.SilkS")
		)
		(fp_line
			(start -1.4 1)
			(end -1.4 -1)
			(stroke
				(width 0.05)
				(type solid)
			)
			(layer "F.CrtYd")
		)
		(fp_line
			(start -0.9 -1.3)
			(end -0.9 -1)
			(stroke
				(width 0.05)
				(type solid)
			)
			(layer "F.CrtYd")
		)
		(fp_line
			(start -0.9 -1.3)
			(end 0.9 -1.3)
			(stroke
				(width 0.05)
				(type solid)
			)
			(layer "F.CrtYd")
		)
		(fp_line
			(start -0.9 -1)
			(end -1.4 -1)
			(stroke
				(width 0.05)
				(type solid)
			)
			(layer "F.CrtYd")
		)
		(fp_line
			(start -0.9 1)
			(end -1.4 1)
			(stroke
				(width 0.05)
				(type solid)
			)
			(layer "F.CrtYd")
		)
		(fp_line
			(start -0.9 1.3)
			(end -0.9 1)
			(stroke
				(width 0.05)
				(type solid)
			)
			(layer "F.CrtYd")
		)
		(fp_line
			(start 0.9 -1.3)
			(end 0.9 -0.4)
			(stroke
				(width 0.05)
				(type solid)
			)
			(layer "F.CrtYd")
		)
		(fp_line
			(start 0.9 -0.4)
			(end 1.4 -0.4)
			(stroke
				(width 0.05)
				(type solid)
			)
			(layer "F.CrtYd")
		)
		(fp_line
			(start 0.9 0.4)
			(end 0.9 1.3)
			(stroke
				(width 0.05)
				(type solid)
			)
			(layer "F.CrtYd")
		)
		(fp_line
			(start 0.9 1.3)
			(end -0.9 1.3)
			(stroke
				(width 0.05)
				(type solid)
			)
			(layer "F.CrtYd")
		)
		(fp_line
			(start 1.4 -0.4)
			(end 1.4 0.4)
			(stroke
				(width 0.05)
				(type solid)
			)
			(layer "F.CrtYd")
		)
		(fp_line
			(start 1.4 0.4)
			(end 0.9 0.4)
			(stroke
				(width 0.05)
				(type solid)
			)
			(layer "F.CrtYd")
		)
		(fp_rect
			(start -0.623 -0.999)
			(end 0.627 1.001)
			(stroke
				(width 0.15)
				(type solid)
			)
			(fill no)
			(layer "F.Fab")
		)
		(pad "1" smd rect
			(at -1.051 -0.65 90)
			(size 0.6 0.6)
			(layers "F.Cu" "F.Mask" "F.Paste")
			(net 1307 "/USER_IO.LED_BLUE")
			(pinfunction "G")
			(pintype "passive")
		)
		(pad "2" smd rect
			(at -1.051 0.65 90)
			(size 0.6 0.6)
			(layers "F.Cu" "F.Mask" "F.Paste")
			(net 1 "GND")
			(pinfunction "S")
			(pintype "passive")
		)
		(pad "3" smd rect
			(at 1.05 0 90)
			(size 0.6 0.6)
			(layers "F.Cu" "F.Mask" "F.Paste")
			(net 787 "Net-(D25-C)")
			(pinfunction "D")
			(pintype "passive")
		)
	)
	(footprint "antmicro-footprints:SOT-23-6"
		(layer "F.Cu")
		(at 159.95 187.1)
		(property "Reference" "U33"
			(at -1.02 2.79 0)
			(layer "F.SilkS")
			(effects
				(font
					(size 0.7 0.7)
					(thickness 0.15)
				)
				(justify left bottom)
			)
		)
		(property "Value" "MAX16150A_SOT"
			(at -1.75 2.75 0)
			(layer "F.Fab")
			(effects
				(font
					(size 0.7 0.7)
					(thickness 0.15)
				)
				(justify left bottom)
			)
		)
		(property "Description" "Push Button On/Off Controller, Latched Output, 1.3 to 5.5 V Supply, 50 ms Debounce Time, SOT-23-6"
			(at 0 0 0)
			(layer "F.Fab")
			(hide yes)
			(effects
				(font
					(size 1.27 1.27)
					(thickness 0.15)
				)
			)
		)
		(property "Author" "Antmicro"
			(at 0 0 0)
			(layer "F.Fab")
			(hide yes)
			(effects
				(font
					(size 1 1)
					(thickness 0.15)
				)
			)
		)
		(property "License" "Apache-2.0"
			(at 0 0 0)
			(layer "F.Fab")
			(hide yes)
			(effects
				(font
					(size 1 1)
					(thickness 0.15)
				)
			)
		)
		(property "MPN" "MAX16150AUT+T"
			(at 0 0 0)
			(layer "F.Fab")
			(hide yes)
			(effects
				(font
					(size 1 1)
					(thickness 0.15)
				)
			)
		)
		(property "Manufacturer" "Maxim Integrated Products"
			(at 0 0 0)
			(layer "F.Fab")
			(hide yes)
			(effects
				(font
					(size 1 1)
					(thickness 0.15)
				)
			)
		)
		(sheetname "DC-DC Converters")
		(sheetfile "dc-dc.kicad_sch")
		(attr smd)
		(fp_line
			(start -1.45 -0.7)
			(end -1.45 -0.4)
			(stroke
				(width 0.12)
				(type solid)
			)
			(layer "F.SilkS")
		)
		(fp_line
			(start -1.45 0.7)
			(end -1.45 0.4)
			(stroke
				(width 0.12)
				(type solid)
			)
			(layer "F.SilkS")
		)
		(fp_line
			(start -1.3 -0.7)
			(end -1.45 -0.7)
			(stroke
				(width 0.12)
				(type solid)
			)
			(layer "F.SilkS")
		)
		(fp_line
			(start 1.3 -0.7)
			(end 1.45 -0.7)
			(stroke
				(width 0.12)
				(type solid)
			)
			(layer "F.SilkS")
		)
		(fp_line
			(start 1.3 0.7)
			(end 1.45 0.7)
			(stroke
				(width 0.12)
				(type solid)
			)
			(layer "F.SilkS")
		)
		(fp_line
			(start 1.45 -0.7)
			(end 1.45 -0.4)
			(stroke
				(width 0.12)
				(type solid)
			)
			(layer "F.SilkS")
		)
		(fp_line
			(start 1.45 0.7)
			(end 1.45 0.4)
			(stroke
				(width 0.12)
				(type solid)
			)
			(layer "F.SilkS")
		)
		(fp_rect
			(start -1.55 -1.85)
			(end 1.55 1.75)
			(stroke
				(width 0.05)
				(type solid)
			)
			(fill no)
			(layer "F.CrtYd")
		)
		(fp_line
			(start -1.5 -0.7)
			(end 1.5 -0.7)
			(stroke
				(width 0.1)
				(type solid)
			)
			(layer "F.Fab")
		)
		(fp_line
			(start -1.5 0.7)
			(end -1.5 -0.7)
			(stroke
				(width 0.1)
				(type solid)
			)
			(layer "F.Fab")
		)
		(fp_line
			(start 1.5 -0.7)
			(end 1.5 0.7)
			(stroke
				(width 0.1)
				(type solid)
			)
			(layer "F.Fab")
		)
		(fp_line
			(start 1.5 0.7)
			(end -1.5 0.7)
			(stroke
				(width 0.1)
				(type solid)
			)
			(layer "F.Fab")
		)
		(fp_text user "."
			(at -1.4 1.2 180)
			(layer "F.SilkS")
			(effects
				(font
					(size 1 1)
					(thickness 0.15)
				)
			)
		)
		(pad "1" smd roundrect
			(at -0.954 1.1)
			(size 0.55 1)
			(layers "F.Cu" "F.Mask" "F.Paste")
			(roundrect_rratio 0.15)
			(net 974 "/DC-DC Converters/~{PB_CTRL_IN}")
			(pinfunction "~{PB_IN}")
			(pintype "input")
		)
		(pad "2" smd roundrect
			(at -0.003 1.1)
			(size 0.55 1)
			(layers "F.Cu" "F.Mask" "F.Paste")
			(roundrect_rratio 0.15)
			(net 1 "GND")
			(pinfunction "GND")
			(pintype "power_in")
		)
		(pad "3" smd roundrect
			(at 0.947 1.1)
			(size 0.55 1)
			(layers "F.Cu" "F.Mask" "F.Paste")
			(roundrect_rratio 0.15)
			(net 37 "+3V3_AON")
			(pinfunction "VCC")
			(pintype "power_in")
		)
		(pad "4" smd roundrect
			(at 0.947 -1.214)
			(size 0.55 1)
			(layers "F.Cu" "F.Mask" "F.Paste")
			(roundrect_rratio 0.15)
			(net 701 "/DC-DC Converters/PB_CTRL_OUT")
			(pinfunction "OUT")
			(pintype "output")
		)
		(pad "5" smd roundrect
			(at -0.003 -1.214)
			(size 0.55 1)
			(layers "F.Cu" "F.Mask" "F.Paste")
			(roundrect_rratio 0.15)
			(net 577 "/DC-DC Converters/PB_CTRL.~{PB_CTRL_INT}")
			(pinfunction "~{INT}")
			(pintype "output")
		)
		(pad "6" smd roundrect
			(at -0.954 -1.214)
			(size 0.55 1)
			(layers "F.Cu" "F.Mask" "F.Paste")
			(roundrect_rratio 0.15)
			(net 1340 "/SUP_MCU.SW_STATE")
			(pinfunction "~{CLR}")
			(pintype "input")
		)
	)
	(footprint "antmicro-footprints:R_0603_1608Metric"
		(layer "F.Cu")
		(at 152.3 172.7 90)
		(descr "Resistor SMD 0603")
		(tags "resistor SMD 0603")
		(property "Reference" "R288"
			(at 2.975 -1.575 315)
			(unlocked yes)
			(layer "F.SilkS")
			(effects
				(font
					(size 0.7 0.7)
					(thickness 0.15)
				)
				(justify left bottom)
			)
		)
		(property "Value" "R_0R_22.4A_0603"
			(at 0 1.6 90)
			(layer "F.Fab")
			(effects
				(font
					(size 0.7 0.7)
					(thickness 0.15)
				)
				(justify left bottom)
			)
		)
		(property "Description" "SMD Chip Resistor"
			(at 0 0 90)
			(layer "F.Fab")
			(hide yes)
			(effects
				(font
					(size 1.27 1.27)
					(thickness 0.15)
				)
			)
		)
		(property "Author" "Antmicro"
			(at 325 20.4 0)
			(layer "F.Fab")
			(hide yes)
			(effects
				(font
					(size 1 1)
					(thickness 0.15)
				)
			)
		)
		(property "License" "Apache-2.0"
			(at 325 20.4 0)
			(layer "F.Fab")
			(hide yes)
			(effects
				(font
					(size 1 1)
					(thickness 0.15)
				)
			)
		)
		(property "MPN" "PMR03EZPJ000"
			(at 325 20.4 0)
			(layer "F.Fab")
			(hide yes)
			(effects
				(font
					(size 1 1)
					(thickness 0.15)
				)
			)
		)
		(property "Manufacturer" "ROHM Semiconductor"
			(at 325 20.4 0)
			(layer "F.Fab")
			(hide yes)
			(effects
				(font
					(size 1 1)
					(thickness 0.15)
				)
			)
		)
		(property "Max. Curr." "22.4A"
			(at 325 20.4 0)
			(layer "F.Fab")
			(hide yes)
			(effects
				(font
					(size 1 1)
					(thickness 0.15)
				)
			)
		)
		(property "Tolerance" "template_tolerance"
			(at 325 20.4 0)
			(layer "F.Fab")
			(hide yes)
			(effects
				(font
					(size 1 1)
					(thickness 0.15)
				)
			)
		)
		(property "Val" "0R"
			(at 325 20.4 0)
			(layer "F.Fab")
			(hide yes)
			(effects
				(font
					(size 1 1)
					(thickness 0.15)
				)
			)
		)
		(sheetname "DC-DC Converters")
		(sheetfile "dc-dc.kicad_sch")
		(attr smd)
		(fp_line
			(start -0.15 -0.4)
			(end 0.15 -0.4)
			(stroke
				(width 0.15)
				(type solid)
			)
			(layer "F.SilkS")
		)
		(fp_line
			(start -0.15 0.4)
			(end 0.15 0.4)
			(stroke
				(width 0.15)
				(type solid)
			)
			(layer "F.SilkS")
		)
		(fp_rect
			(start -1.25 -0.65)
			(end 1.25 0.65)
			(stroke
				(width 0.05)
				(type solid)
			)
			(fill no)
			(layer "F.CrtYd")
		)
		(fp_rect
			(start -0.8 -0.4)
			(end 0.8 0.4)
			(stroke
				(width 0.15)
				(type solid)
			)
			(fill no)
			(layer "F.Fab")
		)
		(pad "1" smd roundrect
			(at -0.7 0 90)
			(size 0.8 1)
			(layers "F.Cu" "F.Mask" "F.Paste")
			(roundrect_rratio 0.2)
			(net 738 "/DC-DC Converters/1V7_local")
			(pintype "passive")
		)
		(pad "2" smd roundrect
			(at 0.7 0 90)
			(size 0.8 1)
			(layers "F.Cu" "F.Mask" "F.Paste")
			(roundrect_rratio 0.2)
			(net 743 "/DC-DC Converters/1V7")
			(pintype "passive")
		)
	)
)
